FILE_TYPE = MACRO_DRAWING;
SET COLOR_WIRE YELLOW;
SET COLOR_PROP ORANGE;
SET COLOR_DOT WHITE;
SET COLOR_ARC YELLOW;
SET COLOR_BODY GREEN;
SET COLOR_NOTE PURPLE;
SET PROP_DISPLAY VALUE;
SET PAGE_NUMBER P250;
FORCEADD QUANTA_TITLE_BLOCK_C..1
(0 0);
FORCEPROP 1 LAST CUSTOM_TXT_CDS <NAME_2>
J 0
(-3175 50);
FORCEPROP 1 LAST CUSTOM_TXT_CDS <NAME_1>
J 0
(-3175 175);
FORCEPROP 1 LAST CUSTOM_TXT_CDS <Q_NUMBER>
J 0
(-1403 103);
DISPLAY 1.212766 (-1403 103);
FORCEPROP 1 LAST CUSTOM_TXT_CDS <Q_PROJ>
J 0
(-2382 102);
DISPLAY 1.212766 (-2382 102);
FORCEPROP 1 LAST CUSTOM_TXT_CDS <Q_REV>
J 0
(-184 103);
DISPLAY 1.212766 (-184 103);
FORCEPROP 1 LAST CUSTOM_TXT_CDS <CON_LAST_MODIFIED>
J 0
(-1885 15);
DISPLAY 0.978723 (-1885 15);
FORCEPROP 1 LAST CUSTOM_TXT_CDS <CON_PAGE_NUM> OF <CON_TOTAL_PAGES>
J 0
(-446 18);
DISPLAY 0.978723 (-446 18);
FORCEPROP 1 LAST Q_TITLE Blank
J 0
(-9366 26);
DISPLAY 2.446809 (-9366 26);
PAINT GREEN (-9366 26);
FORCEPROP 1 LAST CDS_LMAN_SYM_OUTLINE -9475,6775,100,-125
J 0
(0 0);
DISPLAY 0.468085 (0 0);
PAINT GREEN (0 0);
DISPLAY INVISIBLE (0 0);
FORCEPROP 2 LAST CDS_LIB pure_quanta
J 0
(0 0);
DISPLAY INVISIBLE (0 0);
FORCEPROP 2 LAST PAGE_BORDER TRUE
J 0
(-7890 5250);
DISPLAY 0.638298 (-7890 5250);
PAINT PINK (-7890 5250);
DISPLAY INVISIBLE (-7890 5250);
FORCEPROP 2 LAST CDS_XR_PAGE_TITLE CR-250 : @T6G_MB_LIB.T6G(SCH_1):PAGE250
J 0
(-7890 5250);
DISPLAY 0.638298 (-7890 5250);
PAINT PINK (-7890 5250);
DISPLAY INVISIBLE (-7890 5250);
FORCEPROP 2 LAST CUSTOM_TXT_CDS <XR_PAGE_TITLE>
J 0
(-7890 5250);
DISPLAY 0.638298 (-7890 5250);
PAINT PINK (-7890 5250);
DISPLAY INVISIBLE (-7890 5250);
FORCEPROP 1 LAST COMMENT_BODY TRUE
J 0
(12 -13);
DISPLAY 0.978723 (12 -13);
PAINT GREEN (12 -13);
DISPLAY INVISIBLE (12 -13);
FORCEPROP 1 LAST Q_DEPT BU9
J 1
(-3763 49);
DISPLAY 1.957447 (-3763 49);
PAINT GREEN (-3763 49);
DISPLAY INVISIBLE (-3763 49);
FORCEPROP 0 LAST CDS_CON_LAST_MODIFIED Thu Aug 24 10:15:45 2023
J 0
(-1885 15);
DISPLAY INVISIBLE (-1885 15);
QUIT
